# T6G (Grand Teton) — schematic netlist excerpt (pin names and nets, part order shuffled) for the footprints in the layout excerpt that follows; sources: Cadence DE-HDL packaged netlist, KiCad conversion of 04192023_DAF0TMB3IC0_F0TG_MB_C_brd_V02_OCP.brd

R1301  Q_RES  10 1% CHIP  pkg 0402LF  page 357 : A = P12V_OCP_SFF_R ; B = VSENSE_P12V_INA230_6_INN
R47  Q_RES  200 1% CHIP  pkg 0402LF  page 131 : A = SMB_OCP_SFF_3V3AUX_BUF_R_SCL ; B = SMB_OCP_SFF_3V3AUX_BUF_SCL

(kicad_pcb
	(version 20260206)
	(generator "pcbnew")
	(generator_version "10.0")
	(general
		(thickness 1.6)
		(legacy_teardrops no)
	)
	(paper "A4")
	(title_block
		(title "04192023_DAF0TMB3IC0_F0TG_MB_C_brd_V02_OCP.brd")
		(comment 1 "Grand Teton / footprints 80-81 of 8354")
	)
	(layers
		(0 "F.Cu" signal "TOP")
		(4 "In1.Cu" signal "GND")
		(6 "In2.Cu" signal "IN1")
		(8 "In3.Cu" signal "GND1")
		(10 "In4.Cu" signal "IN2")
		(12 "In5.Cu" signal "GND2")
		(14 "In6.Cu" signal "IN3")
		(16 "In7.Cu" signal "GND3")
		(18 "In8.Cu" signal "VCC")
		(20 "In9.Cu" signal "VCC1")
		(22 "In10.Cu" signal "GND4")
		(24 "In11.Cu" signal "IN4")
		(26 "In12.Cu" signal "GND5")
		(28 "In13.Cu" signal "IN5")
		(30 "In14.Cu" signal "GND6")
		(32 "In15.Cu" signal "IN6")
		(34 "In16.Cu" signal "GND7")
		(2 "B.Cu" signal "BOTTOM")
		(9 "F.Adhes" user "F.Adhesive")
		(11 "B.Adhes" user "B.Adhesive")
		(13 "F.Paste" user "Package Geometry/Pastemask Top")
		(15 "B.Paste" user "Package Geometry/Pastemask Bottom")
		(5 "F.SilkS" user "Ref Des/Silkscreen Top")
		(7 "B.SilkS" user "Ref Des/Silkscreen Bottom")
		(1 "F.Mask" user "Board Geometry/Soldermask Top")
		(3 "B.Mask" user "Board Geometry/Soldermask Bottom")
		(17 "Dwgs.User" user "User.Drawings")
		(19 "Cmts.User" user "User.Comments")
		(21 "Eco1.User" user "User.Eco1")
		(23 "Eco2.User" user "User.Eco2")
		(25 "Edge.Cuts" user "Board Geometry/Outline")
		(27 "Margin" user)
		(31 "F.CrtYd" user "Package Geometry/Place Bound Top")
		(29 "B.CrtYd" user "Package Geometry/Place Bound Bottom")
		(35 "F.Fab" user "Ref Des/Assembly Top")
		(33 "B.Fab" user "Ref Des/Assembly Bottom")
	)
	(footprint ""
		(layer "F.Cu")
		(at 441.530486 -21.676106)
		(property "Reference" "R1301"
			(at 0 0 0)
			(layer "F.SilkS")
			(hide yes)
			(effects
				(font
					(size 1.27 1.27)
				)
			)
		)
		(property "Value" ""
			(at 0 0 0)
			(layer "F.Fab")
			(effects
				(font
					(size 1.27 1.27)
				)
			)
		)
		(duplicate_pad_numbers_are_jumpers no)
		(fp_line
			(start -0.7874 -0.4064)
			(end 0.7874 -0.4064)
			(stroke
				(width 0.1524)
				(type default)
			)
			(layer "F.SilkS")
		)
		(fp_line
			(start -0.7874 0.4064)
			(end -0.7874 -0.4064)
			(stroke
				(width 0.1524)
				(type default)
			)
			(layer "F.SilkS")
		)
		(fp_line
			(start 0.7874 -0.4064)
			(end 0.7874 0.4064)
			(stroke
				(width 0.1524)
				(type default)
			)
			(layer "F.SilkS")
		)
		(fp_line
			(start 0.7874 0.4064)
			(end -0.7874 0.4064)
			(stroke
				(width 0.1524)
				(type default)
			)
			(layer "F.SilkS")
		)
		(fp_line
			(start -0.67945 -0.305054)
			(end -0.12065 -0.305054)
			(stroke
				(width 0.1)
				(type default)
			)
			(layer "F.Fab")
		)
		(fp_line
			(start -0.67945 0.3048)
			(end -0.67945 -0.305054)
			(stroke
				(width 0.1)
				(type default)
			)
			(layer "F.Fab")
		)
		(fp_line
			(start -0.12065 -0.305054)
			(end -0.12065 -0.2794)
			(stroke
				(width 0.1)
				(type default)
			)
			(layer "F.Fab")
		)
		(fp_line
			(start -0.12065 -0.2794)
			(end 0.12065 -0.2794)
			(stroke
				(width 0.1)
				(type default)
			)
			(layer "F.Fab")
		)
		(fp_line
			(start -0.12065 0.2794)
			(end -0.12065 0.3048)
			(stroke
				(width 0.1)
				(type default)
			)
			(layer "F.Fab")
		)
		(fp_line
			(start -0.12065 0.3048)
			(end -0.67945 0.3048)
			(stroke
				(width 0.1)
				(type default)
			)
			(layer "F.Fab")
		)
		(fp_line
			(start 0.120396 0.2794)
			(end -0.12065 0.2794)
			(stroke
				(width 0.1)
				(type default)
			)
			(layer "F.Fab")
		)
		(fp_line
			(start 0.120396 0.3048)
			(end 0.120396 0.2794)
			(stroke
				(width 0.1)
				(type default)
			)
			(layer "F.Fab")
		)
		(fp_line
			(start 0.12065 -0.3048)
			(end 0.67945 -0.3048)
			(stroke
				(width 0.1)
				(type default)
			)
			(layer "F.Fab")
		)
		(fp_line
			(start 0.12065 -0.2794)
			(end 0.12065 -0.3048)
			(stroke
				(width 0.1)
				(type default)
			)
			(layer "F.Fab")
		)
		(fp_line
			(start 0.67945 -0.3048)
			(end 0.67945 0.3048)
			(stroke
				(width 0.1)
				(type default)
			)
			(layer "F.Fab")
		)
		(fp_line
			(start 0.67945 0.3048)
			(end 0.120396 0.3048)
			(stroke
				(width 0.1)
				(type default)
			)
			(layer "F.Fab")
		)
		(pad "1" smd circle
			(at -0.40005 0)
			(size 0 0)
			(layers "F.Cu" "F.Mask" "F.Paste")
			(net "P12V_OCP_SFF_R")
		)
		(pad "2" smd circle
			(at 0.40005 0)
			(size 0 0)
			(layers "F.Cu" "F.Mask" "F.Paste")
			(net "VSENSE_P12V_INA230_6_INN")
		)
	)
	(footprint ""
		(layer "F.Cu")
		(at 412.472886 -76.896468 180)
		(property "Reference" "R47"
			(at 0 0 180)
			(layer "F.SilkS")
			(hide yes)
			(effects
				(font
					(size 1.27 1.27)
				)
			)
		)
		(property "Value" ""
			(at 0 0 180)
			(layer "F.Fab")
			(effects
				(font
					(size 1.27 1.27)
				)
			)
		)
		(duplicate_pad_numbers_are_jumpers no)
		(fp_line
			(start 0.7874 0.4064)
			(end -0.7874 0.4064)
			(stroke
				(width 0.1524)
				(type default)
			)
			(layer "F.SilkS")
		)
		(fp_line
			(start 0.7874 -0.4064)
			(end 0.7874 0.4064)
			(stroke
				(width 0.1524)
				(type default)
			)
			(layer "F.SilkS")
		)
		(fp_line
			(start -0.7874 0.4064)
			(end -0.7874 -0.4064)
			(stroke
				(width 0.1524)
				(type default)
			)
			(layer "F.SilkS")
		)
		(fp_line
			(start -0.7874 -0.4064)
			(end 0.7874 -0.4064)
			(stroke
				(width 0.1524)
				(type default)
			)
			(layer "F.SilkS")
		)
		(fp_line
			(start 0.67945 0.3048)
			(end 0.120396 0.3048)
			(stroke
				(width 0.1)
				(type default)
			)
			(layer "F.Fab")
		)
		(fp_line
			(start 0.67945 -0.3048)
			(end 0.67945 0.3048)
			(stroke
				(width 0.1)
				(type default)
			)
			(layer "F.Fab")
		)
		(fp_line
			(start 0.12065 -0.2794)
			(end 0.12065 -0.3048)
			(stroke
				(width 0.1)
				(type default)
			)
			(layer "F.Fab")
		)
		(fp_line
			(start 0.12065 -0.3048)
			(end 0.67945 -0.3048)
			(stroke
				(width 0.1)
				(type default)
			)
			(layer "F.Fab")
		)
		(fp_line
			(start 0.120396 0.3048)
			(end 0.120396 0.2794)
			(stroke
				(width 0.1)
				(type default)
			)
			(layer "F.Fab")
		)
		(fp_line
			(start 0.120396 0.2794)
			(end -0.12065 0.2794)
			(stroke
				(width 0.1)
				(type default)
			)
			(layer "F.Fab")
		)
		(fp_line
			(start -0.12065 0.3048)
			(end -0.67945 0.3048)
			(stroke
				(width 0.1)
				(type default)
			)
			(layer "F.Fab")
		)
		(fp_line
			(start -0.12065 0.2794)
			(end -0.12065 0.3048)
			(stroke
				(width 0.1)
				(type default)
			)
			(layer "F.Fab")
		)
		(fp_line
			(start -0.12065 -0.2794)
			(end 0.12065 -0.2794)
			(stroke
				(width 0.1)
				(type default)
			)
			(layer "F.Fab")
		)
		(fp_line
			(start -0.12065 -0.305054)
			(end -0.12065 -0.2794)
			(stroke
				(width 0.1)
				(type default)
			)
			(layer "F.Fab")
		)
		(fp_line
			(start -0.67945 0.3048)
			(end -0.67945 -0.305054)
			(stroke
				(width 0.1)
				(type default)
			)
			(layer "F.Fab")
		)
		(fp_line
			(start -0.67945 -0.305054)
			(end -0.12065 -0.305054)
			(stroke
				(width 0.1)
				(type default)
			)
			(layer "F.Fab")
		)
		(pad "1" smd circle
			(at -0.40005 0 180)
			(size 0 0)
			(layers "F.Cu" "F.Mask" "F.Paste")
			(net "SMB_OCP_SFF_3V3AUX_BUF_R_SCL")
		)
		(pad "2" smd circle
			(at 0.40005 0 180)
			(size 0 0)
			(layers "F.Cu" "F.Mask" "F.Paste")
			(net "SMB_OCP_SFF_3V3AUX_BUF_SCL")
		)
	)
)
